(kicad_pcb
	(version 20260206)
	(generator "pcbnew")
	(generator_version "10.0")
	(general
		(thickness 1.6)
		(legacy_teardrops no)
	)
	(paper "A4")
	(title_block
		(title "03242023_DA0F0TMBIJ0_F0T_Motherboard_J_brd_V01_OCP.brd")
		(comment 1 "Grand Teton / footprints 4684-4689 of 6105")
	)
	(layers
		(0 "F.Cu" signal "TOP")
		(4 "In1.Cu" signal "GND")
		(6 "In2.Cu" signal "IN1")
		(8 "In3.Cu" signal "GND1")
		(10 "In4.Cu" signal "IN2")
		(12 "In5.Cu" signal "GND2")
		(14 "In6.Cu" signal "IN3")
		(16 "In7.Cu" signal "GND3")
		(18 "In8.Cu" signal "VCC")
		(20 "In9.Cu" signal "VCC1")
		(22 "In10.Cu" signal "GND4")
		(24 "In11.Cu" signal "IN4")
		(26 "In12.Cu" signal "GND5")
		(28 "In13.Cu" signal "IN5")
		(30 "In14.Cu" signal "GND6")
		(32 "In15.Cu" signal "IN6")
		(34 "In16.Cu" signal "GND7")
		(2 "B.Cu" signal "BOTTOM")
		(9 "F.Adhes" user "F.Adhesive")
		(11 "B.Adhes" user "B.Adhesive")
		(13 "F.Paste" user "Package Geometry/Pastemask Top")
		(15 "B.Paste" user "Package Geometry/Pastemask Bottom")
		(5 "F.SilkS" user "Ref Des/Silkscreen Top")
		(7 "B.SilkS" user "Ref Des/Silkscreen Bottom")
		(1 "F.Mask" user "Board Geometry/Soldermask Top")
		(3 "B.Mask" user "Board Geometry/Soldermask Bottom")
		(17 "Dwgs.User" user "User.Drawings")
		(19 "Cmts.User" user "User.Comments")
		(21 "Eco1.User" user "User.Eco1")
		(23 "Eco2.User" user "User.Eco2")
		(25 "Edge.Cuts" user "Board Geometry/Outline")
		(27 "Margin" user)
		(31 "F.CrtYd" user "Package Geometry/Place Bound Top")
		(29 "B.CrtYd" user "Package Geometry/Place Bound Bottom")
		(35 "F.Fab" user "Ref Des/Assembly Top")
		(33 "B.Fab" user "Ref Des/Assembly Bottom")
	)
	(footprint ""
		(layer "B.Cu")
		(at 229.33025 -117.960648 -90)
		(property "Reference" "R4495"
			(at 0 0 90)
			(layer "B.SilkS")
			(hide yes)
			(effects
				(font
					(size 1.27 1.27)
				)
				(justify mirror)
			)
		)
		(property "Value" ""
			(at 0 0 90)
			(layer "B.Fab")
			(effects
				(font
					(size 1.27 1.27)
				)
				(justify mirror)
			)
		)
		(duplicate_pad_numbers_are_jumpers no)
		(fp_line
			(start -0.7874 0.4064)
			(end 0.7874 0.4064)
			(stroke
				(width 0.1524)
				(type default)
			)
			(layer "B.SilkS")
		)
		(fp_line
			(start 0.7874 0.4064)
			(end 0.7874 -0.4064)
			(stroke
				(width 0.1524)
				(type default)
			)
			(layer "B.SilkS")
		)
		(fp_line
			(start -0.7874 -0.4064)
			(end -0.7874 0.4064)
			(stroke
				(width 0.1524)
				(type default)
			)
			(layer "B.SilkS")
		)
		(fp_line
			(start 0.7874 -0.4064)
			(end -0.7874 -0.4064)
			(stroke
				(width 0.1524)
				(type default)
			)
			(layer "B.SilkS")
		)
		(fp_line
			(start -0.67945 0.3048)
			(end -0.120396 0.3048)
			(stroke
				(width 0.1)
				(type default)
			)
			(layer "B.Fab")
		)
		(fp_line
			(start -0.120396 0.3048)
			(end -0.120396 0.2794)
			(stroke
				(width 0.1)
				(type default)
			)
			(layer "B.Fab")
		)
		(fp_line
			(start 0.12065 0.3048)
			(end 0.67945 0.3048)
			(stroke
				(width 0.1)
				(type default)
			)
			(layer "B.Fab")
		)
		(fp_line
			(start 0.67945 0.3048)
			(end 0.67945 -0.305054)
			(stroke
				(width 0.1)
				(type default)
			)
			(layer "B.Fab")
		)
		(fp_line
			(start -0.120396 0.2794)
			(end 0.12065 0.2794)
			(stroke
				(width 0.1)
				(type default)
			)
			(layer "B.Fab")
		)
		(fp_line
			(start 0.12065 0.2794)
			(end 0.12065 0.3048)
			(stroke
				(width 0.1)
				(type default)
			)
			(layer "B.Fab")
		)
		(fp_line
			(start -0.12065 -0.2794)
			(end -0.12065 -0.3048)
			(stroke
				(width 0.1)
				(type default)
			)
			(layer "B.Fab")
		)
		(fp_line
			(start 0.12065 -0.2794)
			(end -0.12065 -0.2794)
			(stroke
				(width 0.1)
				(type default)
			)
			(layer "B.Fab")
		)
		(fp_line
			(start -0.67945 -0.3048)
			(end -0.67945 0.3048)
			(stroke
				(width 0.1)
				(type default)
			)
			(layer "B.Fab")
		)
		(fp_line
			(start -0.12065 -0.3048)
			(end -0.67945 -0.3048)
			(stroke
				(width 0.1)
				(type default)
			)
			(layer "B.Fab")
		)
		(fp_line
			(start 0.12065 -0.305054)
			(end 0.12065 -0.2794)
			(stroke
				(width 0.1)
				(type default)
			)
			(layer "B.Fab")
		)
		(fp_line
			(start 0.67945 -0.305054)
			(end 0.12065 -0.305054)
			(stroke
				(width 0.1)
				(type default)
			)
			(layer "B.Fab")
		)
		(pad "1" smd circle
			(at 0.40005 0 90)
			(size 0 0)
			(layers "B.Cu" "B.Mask" "B.Paste")
			(net "OCP_SFF_CLK_OE_R_N")
		)
		(pad "2" smd circle
			(at -0.40005 0 90)
			(size 0 0)
			(layers "B.Cu" "B.Mask" "B.Paste")
			(net "OCP_SFF_CLK_OE_N")
		)
	)
	(footprint ""
		(layer "B.Cu")
		(at 145.415 -9.362948 -90)
		(property "Reference" "R3057"
			(at 0 0 90)
			(layer "B.SilkS")
			(hide yes)
			(effects
				(font
					(size 1.27 1.27)
				)
				(justify mirror)
			)
		)
		(property "Value" ""
			(at 0 0 90)
			(layer "B.Fab")
			(effects
				(font
					(size 1.27 1.27)
				)
				(justify mirror)
			)
		)
		(duplicate_pad_numbers_are_jumpers no)
		(fp_line
			(start -0.7874 0.4064)
			(end 0.7874 0.4064)
			(stroke
				(width 0.1524)
				(type default)
			)
			(layer "B.SilkS")
		)
		(fp_line
			(start 0.7874 0.4064)
			(end 0.7874 -0.4064)
			(stroke
				(width 0.1524)
				(type default)
			)
			(layer "B.SilkS")
		)
		(fp_line
			(start -0.7874 -0.4064)
			(end -0.7874 0.4064)
			(stroke
				(width 0.1524)
				(type default)
			)
			(layer "B.SilkS")
		)
		(fp_line
			(start 0.7874 -0.4064)
			(end -0.7874 -0.4064)
			(stroke
				(width 0.1524)
				(type default)
			)
			(layer "B.SilkS")
		)
		(fp_line
			(start -0.67945 0.3048)
			(end -0.120396 0.3048)
			(stroke
				(width 0.1)
				(type default)
			)
			(layer "B.Fab")
		)
		(fp_line
			(start -0.120396 0.3048)
			(end -0.120396 0.2794)
			(stroke
				(width 0.1)
				(type default)
			)
			(layer "B.Fab")
		)
		(fp_line
			(start 0.12065 0.3048)
			(end 0.67945 0.3048)
			(stroke
				(width 0.1)
				(type default)
			)
			(layer "B.Fab")
		)
		(fp_line
			(start 0.67945 0.3048)
			(end 0.67945 -0.305054)
			(stroke
				(width 0.1)
				(type default)
			)
			(layer "B.Fab")
		)
		(fp_line
			(start -0.120396 0.2794)
			(end 0.12065 0.2794)
			(stroke
				(width 0.1)
				(type default)
			)
			(layer "B.Fab")
		)
		(fp_line
			(start 0.12065 0.2794)
			(end 0.12065 0.3048)
			(stroke
				(width 0.1)
				(type default)
			)
			(layer "B.Fab")
		)
		(fp_line
			(start -0.12065 -0.2794)
			(end -0.12065 -0.3048)
			(stroke
				(width 0.1)
				(type default)
			)
			(layer "B.Fab")
		)
		(fp_line
			(start 0.12065 -0.2794)
			(end -0.12065 -0.2794)
			(stroke
				(width 0.1)
				(type default)
			)
			(layer "B.Fab")
		)
		(fp_line
			(start -0.67945 -0.3048)
			(end -0.67945 0.3048)
			(stroke
				(width 0.1)
				(type default)
			)
			(layer "B.Fab")
		)
		(fp_line
			(start -0.12065 -0.3048)
			(end -0.67945 -0.3048)
			(stroke
				(width 0.1)
				(type default)
			)
			(layer "B.Fab")
		)
		(fp_line
			(start 0.12065 -0.305054)
			(end 0.12065 -0.2794)
			(stroke
				(width 0.1)
				(type default)
			)
			(layer "B.Fab")
		)
		(fp_line
			(start 0.67945 -0.305054)
			(end 0.12065 -0.305054)
			(stroke
				(width 0.1)
				(type default)
			)
			(layer "B.Fab")
		)
		(pad "1" smd circle
			(at 0.40005 0 90)
			(size 0 0)
			(layers "B.Cu" "B.Mask" "B.Paste")
			(net "JTAG_DBP_BMC_PREQ_R1_N")
		)
		(pad "2" smd circle
			(at -0.40005 0 90)
			(size 0 0)
			(layers "B.Cu" "B.Mask" "B.Paste")
			(net "JTAG_BMC_DBP_PREQ_N")
		)
	)
	(footprint ""
		(layer "B.Cu")
		(at 42.392346 -319.268856 180)
		(property "Reference" "R895"
			(at 0 0 0)
			(layer "B.SilkS")
			(hide yes)
			(effects
				(font
					(size 1.27 1.27)
				)
				(justify mirror)
			)
		)
		(property "Value" ""
			(at 0 0 0)
			(layer "B.Fab")
			(effects
				(font
					(size 1.27 1.27)
				)
				(justify mirror)
			)
		)
		(duplicate_pad_numbers_are_jumpers no)
		(fp_line
			(start 0.7874 0.4064)
			(end 0.7874 -0.4064)
			(stroke
				(width 0.1524)
				(type default)
			)
			(layer "B.SilkS")
		)
		(fp_line
			(start 0.7874 -0.4064)
			(end -0.7874 -0.4064)
			(stroke
				(width 0.1524)
				(type default)
			)
			(layer "B.SilkS")
		)
		(fp_line
			(start -0.7874 0.4064)
			(end 0.7874 0.4064)
			(stroke
				(width 0.1524)
				(type default)
			)
			(layer "B.SilkS")
		)
		(fp_line
			(start -0.7874 -0.4064)
			(end -0.7874 0.4064)
			(stroke
				(width 0.1524)
				(type default)
			)
			(layer "B.SilkS")
		)
		(fp_line
			(start 0.67945 0.3048)
			(end 0.67945 -0.305054)
			(stroke
				(width 0.1)
				(type default)
			)
			(layer "B.Fab")
		)
		(fp_line
			(start 0.67945 -0.305054)
			(end 0.12065 -0.305054)
			(stroke
				(width 0.1)
				(type default)
			)
			(layer "B.Fab")
		)
		(fp_line
			(start 0.12065 0.3048)
			(end 0.67945 0.3048)
			(stroke
				(width 0.1)
				(type default)
			)
			(layer "B.Fab")
		)
		(fp_line
			(start 0.12065 0.2794)
			(end 0.12065 0.3048)
			(stroke
				(width 0.1)
				(type default)
			)
			(layer "B.Fab")
		)
		(fp_line
			(start 0.12065 -0.2794)
			(end -0.12065 -0.2794)
			(stroke
				(width 0.1)
				(type default)
			)
			(layer "B.Fab")
		)
		(fp_line
			(start 0.12065 -0.305054)
			(end 0.12065 -0.2794)
			(stroke
				(width 0.1)
				(type default)
			)
			(layer "B.Fab")
		)
		(fp_line
			(start -0.120396 0.3048)
			(end -0.120396 0.2794)
			(stroke
				(width 0.1)
				(type default)
			)
			(layer "B.Fab")
		)
		(fp_line
			(start -0.120396 0.2794)
			(end 0.12065 0.2794)
			(stroke
				(width 0.1)
				(type default)
			)
			(layer "B.Fab")
		)
		(fp_line
			(start -0.12065 -0.2794)
			(end -0.12065 -0.3048)
			(stroke
				(width 0.1)
				(type default)
			)
			(layer "B.Fab")
		)
		(fp_line
			(start -0.12065 -0.3048)
			(end -0.67945 -0.3048)
			(stroke
				(width 0.1)
				(type default)
			)
			(layer "B.Fab")
		)
		(fp_line
			(start -0.67945 0.3048)
			(end -0.120396 0.3048)
			(stroke
				(width 0.1)
				(type default)
			)
			(layer "B.Fab")
		)
		(fp_line
			(start -0.67945 -0.3048)
			(end -0.67945 0.3048)
			(stroke
				(width 0.1)
				(type default)
			)
			(layer "B.Fab")
		)
		(pad "1" smd circle
			(at 0.40005 0)
			(size 0 0)
			(layers "B.Cu" "B.Mask" "B.Paste")
			(net "PWRGD_CHB_CPU1_DIMM1")
		)
		(pad "2" smd circle
			(at -0.40005 0)
			(size 0 0)
			(layers "B.Cu" "B.Mask" "B.Paste")
			(net "PWRGD_FAIL_CPU1_AB")
		)
	)
	(footprint ""
		(layer "B.Cu")
		(at 105.984294 -237.794292 -90)
		(property "Reference" "C1391"
			(at 0 0 90)
			(layer "B.SilkS")
			(hide yes)
			(effects
				(font
					(size 1.27 1.27)
				)
				(justify mirror)
			)
		)
		(property "Value" ""
			(at 0 0 90)
			(layer "B.Fab")
			(effects
				(font
					(size 1.27 1.27)
				)
				(justify mirror)
			)
		)
		(duplicate_pad_numbers_are_jumpers no)
		(fp_line
			(start -1.2954 0.5842)
			(end 1.2954 0.5842)
			(stroke
				(width 0.1524)
				(type default)
			)
			(layer "B.SilkS")
		)
		(fp_line
			(start 1.2954 0.5842)
			(end 1.2954 -0.5842)
			(stroke
				(width 0.1524)
				(type default)
			)
			(layer "B.SilkS")
		)
		(fp_line
			(start -1.2954 -0.5842)
			(end -1.2954 0.5842)
			(stroke
				(width 0.1524)
				(type default)
			)
			(layer "B.SilkS")
		)
		(fp_line
			(start 0 -0.5842)
			(end 0 0.5842)
			(stroke
				(width 0.1524)
				(type default)
			)
			(layer "B.SilkS")
		)
		(fp_line
			(start 1.2954 -0.5842)
			(end -1.2954 -0.5842)
			(stroke
				(width 0.1524)
				(type default)
			)
			(layer "B.SilkS")
		)
		(fp_line
			(start -0.8636 0.4572)
			(end 0.8636 0.4572)
			(stroke
				(width 0.1)
				(type default)
			)
			(layer "B.Fab")
		)
		(fp_line
			(start 0.8636 0.4572)
			(end 0.8636 0.4064)
			(stroke
				(width 0.1)
				(type default)
			)
			(layer "B.Fab")
		)
		(fp_line
			(start -1.1938 0.4064)
			(end -0.8636 0.4064)
			(stroke
				(width 0.1)
				(type default)
			)
			(layer "B.Fab")
		)
		(fp_line
			(start -0.8636 0.4064)
			(end -0.8636 0.4572)
			(stroke
				(width 0.1)
				(type default)
			)
			(layer "B.Fab")
		)
		(fp_line
			(start 0.8636 0.4064)
			(end 1.1938 0.4064)
			(stroke
				(width 0.1)
				(type default)
			)
			(layer "B.Fab")
		)
		(fp_line
			(start 1.1938 0.4064)
			(end 1.1938 -0.4064)
			(stroke
				(width 0.1)
				(type default)
			)
			(layer "B.Fab")
		)
		(fp_line
			(start -1.1938 -0.4064)
			(end -1.1938 0.4064)
			(stroke
				(width 0.1)
				(type default)
			)
			(layer "B.Fab")
		)
		(fp_line
			(start -0.8636 -0.4064)
			(end -1.1938 -0.4064)
			(stroke
				(width 0.1)
				(type default)
			)
			(layer "B.Fab")
		)
		(fp_line
			(start 0.8636 -0.4064)
			(end 0.8636 -0.4572)
			(stroke
				(width 0.1)
				(type default)
			)
			(layer "B.Fab")
		)
		(fp_line
			(start 1.1938 -0.4064)
			(end 0.8636 -0.4064)
			(stroke
				(width 0.1)
				(type default)
			)
			(layer "B.Fab")
		)
		(fp_line
			(start -0.8636 -0.4572)
			(end -0.8636 -0.4064)
			(stroke
				(width 0.1)
				(type default)
			)
			(layer "B.Fab")
		)
		(fp_line
			(start 0.8636 -0.4572)
			(end -0.8636 -0.4572)
			(stroke
				(width 0.1)
				(type default)
			)
			(layer "B.Fab")
		)
		(pad "1" smd rect
			(at 0.7366 0 180)
			(size 0.7112 0.8128)
			(layers "B.Cu" "B.Mask" "B.Paste")
			(net "PVNN_MAIN_CPU1")
		)
		(pad "2" smd rect
			(at -0.7366 0 180)
			(size 0.7112 0.8128)
			(layers "B.Cu" "B.Mask" "B.Paste")
			(net "GND")
		)
	)
	(footprint ""
		(layer "B.Cu")
		(at 243.99748 -128.336548 -90)
		(property "Reference" "R568"
			(at 0 0 90)
			(layer "B.SilkS")
			(hide yes)
			(effects
				(font
					(size 1.27 1.27)
				)
				(justify mirror)
			)
		)
		(property "Value" ""
			(at 0 0 90)
			(layer "B.Fab")
			(effects
				(font
					(size 1.27 1.27)
				)
				(justify mirror)
			)
		)
		(duplicate_pad_numbers_are_jumpers no)
		(fp_line
			(start -0.7874 0.4064)
			(end 0.7874 0.4064)
			(stroke
				(width 0.1524)
				(type default)
			)
			(layer "B.SilkS")
		)
		(fp_line
			(start 0.7874 0.4064)
			(end 0.7874 -0.4064)
			(stroke
				(width 0.1524)
				(type default)
			)
			(layer "B.SilkS")
		)
		(fp_line
			(start -0.7874 -0.4064)
			(end -0.7874 0.4064)
			(stroke
				(width 0.1524)
				(type default)
			)
			(layer "B.SilkS")
		)
		(fp_line
			(start 0.7874 -0.4064)
			(end -0.7874 -0.4064)
			(stroke
				(width 0.1524)
				(type default)
			)
			(layer "B.SilkS")
		)
		(fp_line
			(start -0.67945 0.3048)
			(end -0.120396 0.3048)
			(stroke
				(width 0.1)
				(type default)
			)
			(layer "B.Fab")
		)
		(fp_line
			(start -0.120396 0.3048)
			(end -0.120396 0.2794)
			(stroke
				(width 0.1)
				(type default)
			)
			(layer "B.Fab")
		)
		(fp_line
			(start 0.12065 0.3048)
			(end 0.67945 0.3048)
			(stroke
				(width 0.1)
				(type default)
			)
			(layer "B.Fab")
		)
		(fp_line
			(start 0.67945 0.3048)
			(end 0.67945 -0.305054)
			(stroke
				(width 0.1)
				(type default)
			)
			(layer "B.Fab")
		)
		(fp_line
			(start -0.120396 0.2794)
			(end 0.12065 0.2794)
			(stroke
				(width 0.1)
				(type default)
			)
			(layer "B.Fab")
		)
		(fp_line
			(start 0.12065 0.2794)
			(end 0.12065 0.3048)
			(stroke
				(width 0.1)
				(type default)
			)
			(layer "B.Fab")
		)
		(fp_line
			(start -0.12065 -0.2794)
			(end -0.12065 -0.3048)
			(stroke
				(width 0.1)
				(type default)
			)
			(layer "B.Fab")
		)
		(fp_line
			(start 0.12065 -0.2794)
			(end -0.12065 -0.2794)
			(stroke
				(width 0.1)
				(type default)
			)
			(layer "B.Fab")
		)
		(fp_line
			(start -0.67945 -0.3048)
			(end -0.67945 0.3048)
			(stroke
				(width 0.1)
				(type default)
			)
			(layer "B.Fab")
		)
		(fp_line
			(start -0.12065 -0.3048)
			(end -0.67945 -0.3048)
			(stroke
				(width 0.1)
				(type default)
			)
			(layer "B.Fab")
		)
		(fp_line
			(start 0.12065 -0.305054)
			(end 0.12065 -0.2794)
			(stroke
				(width 0.1)
				(type default)
			)
			(layer "B.Fab")
		)
		(fp_line
			(start 0.67945 -0.305054)
			(end 0.12065 -0.305054)
			(stroke
				(width 0.1)
				(type default)
			)
			(layer "B.Fab")
		)
		(pad "1" smd circle
			(at 0.40005 0 90)
			(size 0 0)
			(layers "B.Cu" "B.Mask" "B.Paste")
			(net "PD_DB2000_SMB_SA1")
		)
		(pad "2" smd circle
			(at -0.40005 0 90)
			(size 0 0)
			(layers "B.Cu" "B.Mask" "B.Paste")
			(net "GND")
		)
	)
	(footprint ""
		(layer "B.Cu")
		(at 193.501518 -319.423288 180)
		(property "Reference" "R906"
			(at 0 0 0)
			(layer "B.SilkS")
			(hide yes)
			(effects
				(font
					(size 1.27 1.27)
				)
				(justify mirror)
			)
		)
		(property "Value" ""
			(at 0 0 0)
			(layer "B.Fab")
			(effects
				(font
					(size 1.27 1.27)
				)
				(justify mirror)
			)
		)
		(duplicate_pad_numbers_are_jumpers no)
		(fp_line
			(start 0.7874 0.4064)
			(end 0.7874 -0.4064)
			(stroke
				(width 0.1524)
				(type default)
			)
			(layer "B.SilkS")
		)
		(fp_line
			(start 0.7874 -0.4064)
			(end -0.7874 -0.4064)
			(stroke
				(width 0.1524)
				(type default)
			)
			(layer "B.SilkS")
		)
		(fp_line
			(start -0.7874 0.4064)
			(end 0.7874 0.4064)
			(stroke
				(width 0.1524)
				(type default)
			)
			(layer "B.SilkS")
		)
		(fp_line
			(start -0.7874 -0.4064)
			(end -0.7874 0.4064)
			(stroke
				(width 0.1524)
				(type default)
			)
			(layer "B.SilkS")
		)
		(fp_line
			(start 0.67945 0.3048)
			(end 0.67945 -0.305054)
			(stroke
				(width 0.1)
				(type default)
			)
			(layer "B.Fab")
		)
		(fp_line
			(start 0.67945 -0.305054)
			(end 0.12065 -0.305054)
			(stroke
				(width 0.1)
				(type default)
			)
			(layer "B.Fab")
		)
		(fp_line
			(start 0.12065 0.3048)
			(end 0.67945 0.3048)
			(stroke
				(width 0.1)
				(type default)
			)
			(layer "B.Fab")
		)
		(fp_line
			(start 0.12065 0.2794)
			(end 0.12065 0.3048)
			(stroke
				(width 0.1)
				(type default)
			)
			(layer "B.Fab")
		)
		(fp_line
			(start 0.12065 -0.2794)
			(end -0.12065 -0.2794)
			(stroke
				(width 0.1)
				(type default)
			)
			(layer "B.Fab")
		)
		(fp_line
			(start 0.12065 -0.305054)
			(end 0.12065 -0.2794)
			(stroke
				(width 0.1)
				(type default)
			)
			(layer "B.Fab")
		)
		(fp_line
			(start -0.120396 0.3048)
			(end -0.120396 0.2794)
			(stroke
				(width 0.1)
				(type default)
			)
			(layer "B.Fab")
		)
		(fp_line
			(start -0.120396 0.2794)
			(end 0.12065 0.2794)
			(stroke
				(width 0.1)
				(type default)
			)
			(layer "B.Fab")
		)
		(fp_line
			(start -0.12065 -0.2794)
			(end -0.12065 -0.3048)
			(stroke
				(width 0.1)
				(type default)
			)
			(layer "B.Fab")
		)
		(fp_line
			(start -0.12065 -0.3048)
			(end -0.67945 -0.3048)
			(stroke
				(width 0.1)
				(type default)
			)
			(layer "B.Fab")
		)
		(fp_line
			(start -0.67945 0.3048)
			(end -0.120396 0.3048)
			(stroke
				(width 0.1)
				(type default)
			)
			(layer "B.Fab")
		)
		(fp_line
			(start -0.67945 -0.3048)
			(end -0.67945 0.3048)
			(stroke
				(width 0.1)
				(type default)
			)
			(layer "B.Fab")
		)
		(pad "1" smd circle
			(at 0.40005 0)
			(size 0 0)
			(layers "B.Cu" "B.Mask" "B.Paste")
			(net "PWRGD_CHG_CPU1_DIMM2")
		)
		(pad "2" smd circle
			(at -0.40005 0)
			(size 0 0)
			(layers "B.Cu" "B.Mask" "B.Paste")
			(net "PWRGD_FAIL_CPU1_GH")
		)
	)
)
